# T6G (Grand Teton) — schematic netlist excerpt (pin names and nets, part order shuffled) for the footprints in the layout excerpt that follows; sources: Cadence DE-HDL packaged netlist, KiCad conversion of 04192023_DAF0TMB3IC0_F0TG_MB_C_brd_V02_OCP.brd

R9002  Q_RES  10K 1% CHIP  pkg 0402LF  page 123 : A = P3V3_AUX ; B = PRSNT_CABLE_SWB_B1_N
H8028  HOLE  EMPTY  pkg TH  page 230 : \1\ = GND
R9016  Q_RES  4.7K 5% CHIP  pkg 0402LF  page 123 : A = P3V3_AUX ; B = PRSNT_CABLE_GPU_A3
R1124  Q_RES  200 1% CHIP  pkg 0201LF  page 310 : A = RT_CPU0_P3_VQPS ; B = GND

(kicad_pcb
	(version 20260206)
	(generator "pcbnew")
	(generator_version "10.0")
	(general
		(thickness 1.6)
		(legacy_teardrops no)
	)
	(paper "A4")
	(title_block
		(title "04192023_DAF0TMB3IC0_F0TG_MB_C_brd_V02_OCP.brd")
		(comment 1 "Grand Teton / footprints 2290-2293 of 8354")
	)
	(layers
		(0 "F.Cu" signal "TOP")
		(4 "In1.Cu" signal "GND")
		(6 "In2.Cu" signal "IN1")
		(8 "In3.Cu" signal "GND1")
		(10 "In4.Cu" signal "IN2")
		(12 "In5.Cu" signal "GND2")
		(14 "In6.Cu" signal "IN3")
		(16 "In7.Cu" signal "GND3")
		(18 "In8.Cu" signal "VCC")
		(20 "In9.Cu" signal "VCC1")
		(22 "In10.Cu" signal "GND4")
		(24 "In11.Cu" signal "IN4")
		(26 "In12.Cu" signal "GND5")
		(28 "In13.Cu" signal "IN5")
		(30 "In14.Cu" signal "GND6")
		(32 "In15.Cu" signal "IN6")
		(34 "In16.Cu" signal "GND7")
		(2 "B.Cu" signal "BOTTOM")
		(9 "F.Adhes" user "F.Adhesive")
		(11 "B.Adhes" user "B.Adhesive")
		(13 "F.Paste" user "Package Geometry/Pastemask Top")
		(15 "B.Paste" user "Package Geometry/Pastemask Bottom")
		(5 "F.SilkS" user "Ref Des/Silkscreen Top")
		(7 "B.SilkS" user "Ref Des/Silkscreen Bottom")
		(1 "F.Mask" user "Board Geometry/Soldermask Top")
		(3 "B.Mask" user "Board Geometry/Soldermask Bottom")
		(17 "Dwgs.User" user "User.Drawings")
		(19 "Cmts.User" user "User.Comments")
		(21 "Eco1.User" user "User.Eco1")
		(23 "Eco2.User" user "User.Eco2")
		(25 "Edge.Cuts" user "Board Geometry/Outline")
		(27 "Margin" user)
		(31 "F.CrtYd" user "Package Geometry/Place Bound Top")
		(29 "B.CrtYd" user "Package Geometry/Place Bound Bottom")
		(35 "F.Fab" user "Ref Des/Assembly Top")
		(33 "B.Fab" user "Ref Des/Assembly Bottom")
	)
	(footprint ""
		(layer "F.Cu")
		(at 362.025438 -411.354016)
		(property "Reference" "R9002"
			(at 0 0 0)
			(layer "F.SilkS")
			(hide yes)
			(effects
				(font
					(size 1.27 1.27)
				)
			)
		)
		(property "Value" ""
			(at 0 0 0)
			(layer "F.Fab")
			(effects
				(font
					(size 1.27 1.27)
				)
			)
		)
		(duplicate_pad_numbers_are_jumpers no)
		(fp_line
			(start -0.7874 -0.4064)
			(end 0.7874 -0.4064)
			(stroke
				(width 0.1524)
				(type default)
			)
			(layer "F.SilkS")
		)
		(fp_line
			(start -0.7874 0.4064)
			(end -0.7874 -0.4064)
			(stroke
				(width 0.1524)
				(type default)
			)
			(layer "F.SilkS")
		)
		(fp_line
			(start 0.7874 -0.4064)
			(end 0.7874 0.4064)
			(stroke
				(width 0.1524)
				(type default)
			)
			(layer "F.SilkS")
		)
		(fp_line
			(start 0.7874 0.4064)
			(end -0.7874 0.4064)
			(stroke
				(width 0.1524)
				(type default)
			)
			(layer "F.SilkS")
		)
		(fp_line
			(start -0.67945 -0.305054)
			(end -0.12065 -0.305054)
			(stroke
				(width 0.1)
				(type default)
			)
			(layer "F.Fab")
		)
		(fp_line
			(start -0.67945 0.3048)
			(end -0.67945 -0.305054)
			(stroke
				(width 0.1)
				(type default)
			)
			(layer "F.Fab")
		)
		(fp_line
			(start -0.12065 -0.305054)
			(end -0.12065 -0.2794)
			(stroke
				(width 0.1)
				(type default)
			)
			(layer "F.Fab")
		)
		(fp_line
			(start -0.12065 -0.2794)
			(end 0.12065 -0.2794)
			(stroke
				(width 0.1)
				(type default)
			)
			(layer "F.Fab")
		)
		(fp_line
			(start -0.12065 0.2794)
			(end -0.12065 0.3048)
			(stroke
				(width 0.1)
				(type default)
			)
			(layer "F.Fab")
		)
		(fp_line
			(start -0.12065 0.3048)
			(end -0.67945 0.3048)
			(stroke
				(width 0.1)
				(type default)
			)
			(layer "F.Fab")
		)
		(fp_line
			(start 0.120396 0.2794)
			(end -0.12065 0.2794)
			(stroke
				(width 0.1)
				(type default)
			)
			(layer "F.Fab")
		)
		(fp_line
			(start 0.120396 0.3048)
			(end 0.120396 0.2794)
			(stroke
				(width 0.1)
				(type default)
			)
			(layer "F.Fab")
		)
		(fp_line
			(start 0.12065 -0.3048)
			(end 0.67945 -0.3048)
			(stroke
				(width 0.1)
				(type default)
			)
			(layer "F.Fab")
		)
		(fp_line
			(start 0.12065 -0.2794)
			(end 0.12065 -0.3048)
			(stroke
				(width 0.1)
				(type default)
			)
			(layer "F.Fab")
		)
		(fp_line
			(start 0.67945 -0.3048)
			(end 0.67945 0.3048)
			(stroke
				(width 0.1)
				(type default)
			)
			(layer "F.Fab")
		)
		(fp_line
			(start 0.67945 0.3048)
			(end 0.120396 0.3048)
			(stroke
				(width 0.1)
				(type default)
			)
			(layer "F.Fab")
		)
		(pad "1" smd circle
			(at -0.40005 0)
			(size 0 0)
			(layers "F.Cu" "F.Mask" "F.Paste")
			(net "P3V3_AUX")
		)
		(pad "2" smd circle
			(at 0.40005 0)
			(size 0 0)
			(layers "F.Cu" "F.Mask" "F.Paste")
			(net "PRSNT_CABLE_SWB_B1_N")
		)
	)
	(footprint ""
		(layer "F.Cu")
		(at 359.568242 -406.567386 -90)
		(property "Reference" "R9016"
			(at 0 0 270)
			(layer "F.SilkS")
			(hide yes)
			(effects
				(font
					(size 1.27 1.27)
				)
			)
		)
		(property "Value" ""
			(at 0 0 270)
			(layer "F.Fab")
			(effects
				(font
					(size 1.27 1.27)
				)
			)
		)
		(duplicate_pad_numbers_are_jumpers no)
		(fp_line
			(start -0.7874 0.4064)
			(end -0.7874 -0.4064)
			(stroke
				(width 0.1524)
				(type default)
			)
			(layer "F.SilkS")
		)
		(fp_line
			(start 0.7874 0.4064)
			(end -0.7874 0.4064)
			(stroke
				(width 0.1524)
				(type default)
			)
			(layer "F.SilkS")
		)
		(fp_line
			(start -0.7874 -0.4064)
			(end 0.7874 -0.4064)
			(stroke
				(width 0.1524)
				(type default)
			)
			(layer "F.SilkS")
		)
		(fp_line
			(start 0.7874 -0.4064)
			(end 0.7874 0.4064)
			(stroke
				(width 0.1524)
				(type default)
			)
			(layer "F.SilkS")
		)
		(fp_line
			(start -0.67945 0.3048)
			(end -0.67945 -0.305054)
			(stroke
				(width 0.1)
				(type default)
			)
			(layer "F.Fab")
		)
		(fp_line
			(start -0.12065 0.3048)
			(end -0.67945 0.3048)
			(stroke
				(width 0.1)
				(type default)
			)
			(layer "F.Fab")
		)
		(fp_line
			(start 0.120396 0.3048)
			(end 0.120396 0.2794)
			(stroke
				(width 0.1)
				(type default)
			)
			(layer "F.Fab")
		)
		(fp_line
			(start 0.67945 0.3048)
			(end 0.120396 0.3048)
			(stroke
				(width 0.1)
				(type default)
			)
			(layer "F.Fab")
		)
		(fp_line
			(start -0.12065 0.2794)
			(end -0.12065 0.3048)
			(stroke
				(width 0.1)
				(type default)
			)
			(layer "F.Fab")
		)
		(fp_line
			(start 0.120396 0.2794)
			(end -0.12065 0.2794)
			(stroke
				(width 0.1)
				(type default)
			)
			(layer "F.Fab")
		)
		(fp_line
			(start -0.12065 -0.2794)
			(end 0.12065 -0.2794)
			(stroke
				(width 0.1)
				(type default)
			)
			(layer "F.Fab")
		)
		(fp_line
			(start 0.12065 -0.2794)
			(end 0.12065 -0.3048)
			(stroke
				(width 0.1)
				(type default)
			)
			(layer "F.Fab")
		)
		(fp_line
			(start 0.12065 -0.3048)
			(end 0.67945 -0.3048)
			(stroke
				(width 0.1)
				(type default)
			)
			(layer "F.Fab")
		)
		(fp_line
			(start 0.67945 -0.3048)
			(end 0.67945 0.3048)
			(stroke
				(width 0.1)
				(type default)
			)
			(layer "F.Fab")
		)
		(fp_line
			(start -0.67945 -0.305054)
			(end -0.12065 -0.305054)
			(stroke
				(width 0.1)
				(type default)
			)
			(layer "F.Fab")
		)
		(fp_line
			(start -0.12065 -0.305054)
			(end -0.12065 -0.2794)
			(stroke
				(width 0.1)
				(type default)
			)
			(layer "F.Fab")
		)
		(pad "1" smd circle
			(at -0.40005 0 270)
			(size 0 0)
			(layers "F.Cu" "F.Mask" "F.Paste")
			(net "P3V3_AUX")
		)
		(pad "2" smd circle
			(at 0.40005 0 270)
			(size 0 0)
			(layers "F.Cu" "F.Mask" "F.Paste")
			(net "PRSNT_CABLE_GPU_A3")
		)
	)
	(footprint ""
		(layer "F.Cu")
		(at 54.716172 -167.14597)
		(property "Reference" "H8028"
			(at -5.808218 -4.25069 0)
			(unlocked yes)
			(layer "F.SilkS")
			(effects
				(font
					(size 0.7874 0.5842)
					(thickness 0.1524)
				)
				(justify left)
			)
		)
		(property "Value" ""
			(at 0 0 0)
			(layer "F.Fab")
			(effects
				(font
					(size 1.27 1.27)
				)
			)
		)
		(duplicate_pad_numbers_are_jumpers no)
		(pad "1" thru_hole circle
			(at 0 0)
			(size 6.1976 6.1976)
			(drill 3.7338)
			(layers "*.Cu" "*.Mask")
			(remove_unused_layers no)
			(net "GND")
			(clearance -0.9779)
			(padstack
				(mode front_inner_back)
				(layer "Inner"
					(shape circle)
					(size 5.5372 5.5372)
					(clearance -0.6477)
				)
				(layer "B.Cu"
					(shape circle)
					(size 6.1976 6.1976)
					(clearance -0.9779)
				)
			)
		)
	)
	(footprint ""
		(layer "F.Cu")
		(at 389.653018 -402.7424 -90)
		(property "Reference" "R1124"
			(at 0 0 270)
			(layer "F.SilkS")
			(hide yes)
			(effects
				(font
					(size 1.27 1.27)
				)
			)
		)
		(property "Value" ""
			(at 0 0 270)
			(layer "F.Fab")
			(effects
				(font
					(size 1.27 1.27)
				)
			)
		)
		(duplicate_pad_numbers_are_jumpers no)
		(fp_line
			(start -0.32512 0.175006)
			(end -0.32512 -0.175006)
			(stroke
				(width 0.1)
				(type default)
			)
			(layer "F.Fab")
		)
		(fp_line
			(start 0.32512 0.175006)
			(end -0.32512 0.175006)
			(stroke
				(width 0.1)
				(type default)
			)
			(layer "F.Fab")
		)
		(fp_line
			(start -0.32512 -0.175006)
			(end 0.32512 -0.175006)
			(stroke
				(width 0.1)
				(type default)
			)
			(layer "F.Fab")
		)
		(fp_line
			(start 0.32512 -0.175006)
			(end 0.32512 0.175006)
			(stroke
				(width 0.1)
				(type default)
			)
			(layer "F.Fab")
		)
		(pad "1" smd rect
			(at -0.2667 0 270)
			(size 0.3048 0.381)
			(layers "F.Cu" "F.Mask" "F.Paste")
			(net "RT_CPU0_P3_VQPS")
		)
		(pad "2" smd rect
			(at 0.2667 0 90)
			(size 0.3048 0.381)
			(layers "F.Cu" "F.Mask" "F.Paste")
			(net "GND")
		)
	)
)
